# SCM (Grand Teton) — schematic netlist excerpt (pin names and nets, part order shuffled) for the footprints in the layout excerpt that follows; sources: Cadence DE-HDL packaged netlist, KiCad conversion of 12092022_DA0F0TMDCD0_F0T_Management_Board_D_brd_V3_OCP.brd

C275  Q_CAP  100PF 50V 5% NPO  pkg 0402  page 15 : A = P3V_BAT_SENSOR ; B = GND

DB2  TDR_3P  EMPTY  pkg TH2  page 60
  GND  = T_GND
  IO1  = TDR_SE_50_OHM_IN1
  IO2  = TDR_SE_50_OHM_IN1

U29  74HC1G126GW  IC  pkg TSSOP5_0-65_2-05X1-25  page 29
  \1\  = DEBUG_PORT_PRSNT
  \2\  = SPA_SOUT_SW_DBG
  GND  = GND
  \4\  = DEBUG_PORT_UART_TX
  \5\  = P3V3_AUX

(kicad_pcb
	(version 20260206)
	(generator "pcbnew")
	(generator_version "10.0")
	(general
		(thickness 1.6)
		(legacy_teardrops no)
	)
	(paper "A4")
	(title_block
		(title "12092022_DA0F0TMDCD0_F0T_Management_Board_D_brd_V3_OCP.brd")
		(comment 1 "Grand Teton / footprints 1338-1340 of 1440")
	)
	(layers
		(0 "F.Cu" signal "TOP")
		(4 "In1.Cu" signal "GND")
		(6 "In2.Cu" signal "IN1")
		(8 "In3.Cu" signal "GND1")
		(10 "In4.Cu" signal "IN2")
		(12 "In5.Cu" signal "VCC")
		(14 "In6.Cu" signal "VCC1")
		(16 "In7.Cu" signal "IN3")
		(18 "In8.Cu" signal "GND2")
		(20 "In9.Cu" signal "IN4")
		(22 "In10.Cu" signal "GND3")
		(2 "B.Cu" signal "BOTTOM")
		(9 "F.Adhes" user "F.Adhesive")
		(11 "B.Adhes" user "B.Adhesive")
		(13 "F.Paste" user "Package Geometry/Pastemask Top")
		(15 "B.Paste" user "Package Geometry/Pastemask Bottom")
		(5 "F.SilkS" user "Ref Des/Silkscreen Top")
		(7 "B.SilkS" user "Ref Des/Silkscreen Bottom")
		(1 "F.Mask" user "Board Geometry/Soldermask Top")
		(3 "B.Mask" user "Board Geometry/Soldermask Bottom")
		(17 "Dwgs.User" user "User.Drawings")
		(19 "Cmts.User" user "User.Comments")
		(21 "Eco1.User" user "User.Eco1")
		(23 "Eco2.User" user "User.Eco2")
		(25 "Edge.Cuts" user "Board Geometry/Outline")
		(27 "Margin" user)
		(31 "F.CrtYd" user "Package Geometry/Place Bound Top")
		(29 "B.CrtYd" user "Package Geometry/Place Bound Bottom")
		(35 "F.Fab" user "Ref Des/Assembly Top")
		(33 "B.Fab" user "Ref Des/Assembly Bottom")
	)
	(footprint ""
		(layer "B.Cu")
		(at 47.85487 -72.954134 180)
		(property "Reference" "C275"
			(at 0 0 0)
			(layer "B.SilkS")
			(hide yes)
			(effects
				(font
					(size 1.27 1.27)
				)
				(justify mirror)
			)
		)
		(property "Value" ""
			(at 0 0 0)
			(layer "B.Fab")
			(effects
				(font
					(size 1.27 1.27)
				)
				(justify mirror)
			)
		)
		(duplicate_pad_numbers_are_jumpers no)
		(fp_line
			(start 0.7874 0.4064)
			(end 0.7874 -0.4064)
			(stroke
				(width 0.1524)
				(type default)
			)
			(layer "B.SilkS")
		)
		(fp_line
			(start 0.7874 -0.4064)
			(end -0.7874 -0.4064)
			(stroke
				(width 0.1524)
				(type default)
			)
			(layer "B.SilkS")
		)
		(fp_line
			(start -0.7874 0.4064)
			(end 0.7874 0.4064)
			(stroke
				(width 0.1524)
				(type default)
			)
			(layer "B.SilkS")
		)
		(fp_line
			(start -0.7874 -0.4064)
			(end -0.7874 0.4064)
			(stroke
				(width 0.1524)
				(type default)
			)
			(layer "B.SilkS")
		)
		(fp_line
			(start 0.67945 0.3048)
			(end 0.67945 -0.305054)
			(stroke
				(width 0.1)
				(type default)
			)
			(layer "B.Fab")
		)
		(fp_line
			(start 0.67945 -0.305054)
			(end 0.12065 -0.305054)
			(stroke
				(width 0.1)
				(type default)
			)
			(layer "B.Fab")
		)
		(fp_line
			(start 0.12065 0.3048)
			(end 0.67945 0.3048)
			(stroke
				(width 0.1)
				(type default)
			)
			(layer "B.Fab")
		)
		(fp_line
			(start 0.12065 0.2794)
			(end 0.12065 0.3048)
			(stroke
				(width 0.1)
				(type default)
			)
			(layer "B.Fab")
		)
		(fp_line
			(start 0.12065 -0.2794)
			(end -0.12065 -0.2794)
			(stroke
				(width 0.1)
				(type default)
			)
			(layer "B.Fab")
		)
		(fp_line
			(start 0.12065 -0.305054)
			(end 0.12065 -0.2794)
			(stroke
				(width 0.1)
				(type default)
			)
			(layer "B.Fab")
		)
		(fp_line
			(start -0.120396 0.3048)
			(end -0.120396 0.2794)
			(stroke
				(width 0.1)
				(type default)
			)
			(layer "B.Fab")
		)
		(fp_line
			(start -0.120396 0.2794)
			(end 0.12065 0.2794)
			(stroke
				(width 0.1)
				(type default)
			)
			(layer "B.Fab")
		)
		(fp_line
			(start -0.12065 -0.2794)
			(end -0.12065 -0.3048)
			(stroke
				(width 0.1)
				(type default)
			)
			(layer "B.Fab")
		)
		(fp_line
			(start -0.12065 -0.3048)
			(end -0.67945 -0.3048)
			(stroke
				(width 0.1)
				(type default)
			)
			(layer "B.Fab")
		)
		(fp_line
			(start -0.67945 0.3048)
			(end -0.120396 0.3048)
			(stroke
				(width 0.1)
				(type default)
			)
			(layer "B.Fab")
		)
		(fp_line
			(start -0.67945 -0.3048)
			(end -0.67945 0.3048)
			(stroke
				(width 0.1)
				(type default)
			)
			(layer "B.Fab")
		)
		(pad "1" smd circle
			(at 0.40005 0)
			(size 0 0)
			(layers "B.Cu" "B.Mask" "B.Paste")
			(net "P3V_BAT_SENSOR")
		)
		(pad "2" smd circle
			(at -0.40005 0)
			(size 0 0)
			(layers "B.Cu" "B.Mask" "B.Paste")
			(net "GND")
		)
	)
	(footprint ""
		(layer "B.Cu")
		(at -14.224 -100.584 180)
		(property "Reference" "DB2"
			(at 1.7018 -5.74167 0)
			(unlocked yes)
			(layer "B.SilkS")
			(effects
				(font
					(size 0.7874 0.5842)
					(thickness 0.1524)
				)
				(justify left mirror)
			)
		)
		(property "Value" ""
			(at 0 0 0)
			(layer "B.Fab")
			(effects
				(font
					(size 1.27 1.27)
				)
				(justify mirror)
			)
		)
		(duplicate_pad_numbers_are_jumpers no)
		(fp_line
			(start 3.330702 -4.771136)
			(end -3.330702 -4.771136)
			(stroke
				(width 0.1524)
				(type default)
			)
			(layer "B.SilkS")
		)
		(fp_line
			(start 0 4.011168)
			(end 3.330702 -4.771136)
			(stroke
				(width 0.1524)
				(type default)
			)
			(layer "B.SilkS")
		)
		(fp_line
			(start -3.330702 -4.771136)
			(end 0 4.011168)
			(stroke
				(width 0.1524)
				(type default)
			)
			(layer "B.SilkS")
		)
		(fp_line
			(start 3.330702 -4.771136)
			(end -3.330702 -4.771136)
			(stroke
				(width 0.1)
				(type default)
			)
			(layer "B.Fab")
		)
		(fp_line
			(start 0 4.011168)
			(end 3.330702 -4.771136)
			(stroke
				(width 0.1)
				(type default)
			)
			(layer "B.Fab")
		)
		(fp_line
			(start -3.330702 -4.771136)
			(end 0 4.011168)
			(stroke
				(width 0.1)
				(type default)
			)
			(layer "B.Fab")
		)
		(pad "1" thru_hole circle
			(at 0 0)
			(size 2.159 2.159)
			(drill 1.7018)
			(layers "*.Cu" "*.Mask")
			(remove_unused_layers no)
			(net "T_GND")
			(clearance 0.0254)
			(thermal_gap 0.0254)
		)
		(pad "2" thru_hole circle
			(at 1.27 -3.348736)
			(size 2.159 2.159)
			(drill 1.7018)
			(layers "*.Cu" "*.Mask")
			(remove_unused_layers no)
			(net "TDR_SE_50_OHM_IN1")
			(clearance 0.0254)
			(thermal_gap 0.0254)
		)
		(pad "3" thru_hole circle
			(at -1.27 -3.348736)
			(size 2.159 2.159)
			(drill 1.7018)
			(layers "*.Cu" "*.Mask")
			(remove_unused_layers no)
			(net "TDR_SE_50_OHM_IN1")
			(clearance 0.0254)
			(thermal_gap 0.0254)
		)
	)
	(footprint ""
		(layer "B.Cu")
		(at 58.547 -21.082 -90)
		(property "Reference" "U29"
			(at 1.2065 1.94437 270)
			(unlocked yes)
			(layer "B.SilkS")
			(effects
				(font
					(size 0.7874 0.5842)
					(thickness 0.1524)
				)
				(justify left mirror)
			)
		)
		(property "Value" ""
			(at 0 0 90)
			(layer "B.Fab")
			(effects
				(font
					(size 1.27 1.27)
				)
				(justify mirror)
			)
		)
		(duplicate_pad_numbers_are_jumpers no)
		(fp_line
			(start -1.3462 1.1938)
			(end -1.3462 -1.1938)
			(stroke
				(width 0.1524)
				(type default)
			)
			(layer "B.SilkS")
		)
		(fp_line
			(start 1.3462 1.1938)
			(end -1.3462 1.1938)
			(stroke
				(width 0.1524)
				(type default)
			)
			(layer "B.SilkS")
		)
		(fp_line
			(start -1.3462 -1.1938)
			(end 1.3462 -1.1938)
			(stroke
				(width 0.1524)
				(type default)
			)
			(layer "B.SilkS")
		)
		(fp_line
			(start 1.3462 -1.1938)
			(end 1.3462 1.1684)
			(stroke
				(width 0.1524)
				(type default)
			)
			(layer "B.SilkS")
		)
		(fp_poly
			(pts
				(xy 1.447038 -0.760476) (xy 2.052066 -0.457962) (xy 2.052066 -1.06299)
			)
			(stroke
				(width 0)
				(type default)
			)
			(fill yes)
			(layer "B.SilkS")
		)
		(fp_line
			(start -0.674878 1.124966)
			(end -0.674878 -1.124966)
			(stroke
				(width 0.1)
				(type default)
			)
			(layer "B.Fab")
		)
		(fp_line
			(start 0.674878 1.124966)
			(end -0.674878 1.124966)
			(stroke
				(width 0.1)
				(type default)
			)
			(layer "B.Fab")
		)
		(fp_line
			(start -0.674878 -1.124966)
			(end 0.674878 -1.124966)
			(stroke
				(width 0.1)
				(type default)
			)
			(layer "B.Fab")
		)
		(fp_line
			(start 0.674878 -1.124966)
			(end 0.674878 1.124966)
			(stroke
				(width 0.1)
				(type default)
			)
			(layer "B.Fab")
		)
		(fp_poly
			(pts
				(xy 1.447038 -0.760476) (xy 2.052066 -0.457962) (xy 2.052066 -1.06299)
			)
			(stroke
				(width 0)
				(type default)
			)
			(fill yes)
			(layer "B.Fab")
		)
		(pad "1" smd rect
			(at 0.899922 -0.750062 90)
			(size 0.6096 0.6096)
			(layers "B.Cu" "B.Mask" "B.Paste")
			(net "DEBUG_PORT_PRSNT")
		)
		(pad "2" smd rect
			(at 0.899922 0)
			(size 0.4064 0.6096)
			(layers "B.Cu" "B.Mask" "B.Paste")
			(net "SPA_SOUT_SW_DBG")
		)
		(pad "3" smd rect
			(at 0.899922 0.750062 90)
			(size 0.6096 0.6096)
			(layers "B.Cu" "B.Mask" "B.Paste")
			(net "GND")
		)
		(pad "4" smd rect
			(at -0.899922 0.750062 90)
			(size 0.6096 0.6096)
			(layers "B.Cu" "B.Mask" "B.Paste")
			(net "DEBUG_PORT_UART_TX")
		)
		(pad "5" smd rect
			(at -0.899922 -0.750062 90)
			(size 0.6096 0.6096)
			(layers "B.Cu" "B.Mask" "B.Paste")
			(net "P3V3_AUX")
		)
	)
)
